#ISCELL
  mstr_misc dns *
  *
#ISCELL
  pure_quanta quanta_title_block_c *
  *
#CELL
  pure_quanta q_cap *
  page195_i1
#CELL
  pure_quanta q_cap *
  page195_i10
#ISCELL
  pure_quanta_power universal_gnd *
  page195_i11
#CELL
  pure_quanta q_cap *
  page195_i12
#CELL
  pure_quanta q_res *
  page195_i13
#ISCELL
  pure_quanta_power universal_gnd *
  page195_i14
#CELL
  pure_quanta q_res *
  page195_i15
#ISCELL
  pure_quanta_power vcc_core *
  page195_i16
#ISCELL
  standard offpage *
  page195_i17
#ISCELL
  standard offpage *
  page195_i18
#CELL
  pure_quanta isl99390frztr5935 *
  page195_i19
#ISCELL
  pure_quanta_power universal_gnd *
  page195_i2
#ISCELL
  pure_quanta_power universal_gnd *
  page195_i20
#ISCELL
  pure_quanta_power universal_gnd *
  page195_i21
#CELL
  pure_quanta q_cap *
  page195_i22
#ISCELL
  pure_quanta_power universal_gnd *
  page195_i23
#ISCELL
  standard offpage *
  page195_i24
#ISCELL
  standard offpage *
  page195_i25
#ISCELL
  pure_quanta_power universal_gnd *
  page195_i26
#CELL
  pure_quanta q_cap *
  page195_i27
#CELL
  pure_quanta q_res *
  page195_i28
#ISCELL
  pure_quanta_power vcc_core *
  page195_i29
#ISCELL
  pure_quanta_power universal_gnd *
  page195_i3
#ISCELL
  pure_quanta_power universal_gnd *
  page195_i30
#CELL
  pure_quanta q_cap *
  page195_i31
#ISCELL
  pure_quanta_power universal_gnd *
  page195_i32
#CELL
  pure_quanta q_res *
  page195_i33
#CELL
  pure_quanta q_cap *
  page195_i34
#CELL
  pure_quanta q_res *
  page195_i35
#ISCELL
  pure_quanta_power universal_gnd *
  page195_i36
#CELL
  pure_quanta q_inductor *
  page195_i37
#CELL
  pure_quanta q_cap *
  page195_i38
#CELL
  pure_quanta q_res *
  page195_i39
#CELL
  pure_quanta q_res *
  page195_i4
#CELL
  pure_quanta q_cap *
  page195_i40
#CELL
  pure_quanta q_cap *
  page195_i41
#ISCELL
  pure_quanta_power universal_gnd *
  page195_i42
#CELL
  pure_quanta q_res *
  page195_i43
#CELL
  pure_quanta q_cap *
  page195_i44
#CELL
  pure_quanta q_cap *
  page195_i45
#ISCELL
  pure_quanta_power universal_gnd *
  page195_i46
#CELL
  pure_quanta q_cap *
  page195_i47
#ISCELL
  pure_quanta_power vcc_core *
  page195_i48
#CELL
  pure_quanta q_res *
  page195_i49
#ISCELL
  standard offpage *
  page195_i5
#CELL
  pure_quanta q_inductor4p_14 *
  page195_i50
#ISCELL
  standard offpage *
  page195_i51
#CELL
  pure_quanta q_res *
  page195_i52
#CELL
  pure_quanta q_cap *
  page195_i53
#CELL
  pure_quanta q_cap *
  page195_i54
#CELL
  pure_quanta q_cap *
  page195_i55
#CELL
  pure_quanta q_cap *
  page195_i56
#CELL
  pure_quanta q_cap *
  page195_i57
#ISCELL
  standard offpage *
  page195_i58
#ISCELL
  pure_quanta_power universal_gnd *
  page195_i59
#ISCELL
  standard offpage *
  page195_i6
#CELL
  pure_quanta q_cap *
  page195_i60
#CELL
  pure_quanta q_cap *
  page195_i61
#ISCELL
  pure_quanta_power vcc_core *
  page195_i62
#CELL
  pure_quanta q_inductor4p_14 *
  page195_i63
#ISCELL
  standard offpage *
  page195_i64
#CELL
  pure_quanta q_cap *
  page195_i65
#ISCELL
  pure_quanta_power universal_gnd *
  page195_i66
#CELL
  pure_quanta q_cap *
  page195_i67
#ISCELL
  pure_quanta_power vcc_core *
  page195_i68
#ISCELL
  pure_quanta_power universal_gnd *
  page195_i69
#ISCELL
  standard offpage *
  page195_i7
#CELL
  pure_quanta q_cap *
  page195_i70
#CELL
  pure_quanta q_cap *
  page195_i71
#ISCELL
  pure_quanta_power vcc_core *
  page195_i72
#CELL
  pure_quanta isl99390frztr5935 *
  page195_i73
#ISCELL
  standard offpage *
  page195_i8
#ISCELL
  pure_quanta_power universal_gnd *
  page195_i9
